# S9S_MB_2U (Grand Teton) — schematic netlist excerpt (pin names and nets, part order shuffled) for the footprints in the layout excerpt that follows; sources: Cadence DE-HDL packaged netlist, KiCad conversion of 03242023_DA0F0TMBIJ0_F0T_Motherboard_J_brd_V01_OCP.brd

C976  Q_CAP  10UF 6.3V 20% X6S  pkg C0402  page 74 : A = PVCCIN_CPU0 ; B = GND
C1978  Q_CAP  1000PF 50V 5% EMPTY  pkg 0402  page 147 : A = GPU_PRSNT_N_ISO ; B = GND
C1333  Q_CAP  10UF 16V 10% X6S  pkg C0805  page 260 : A = P3V3_AUX ; B = GND

(kicad_pcb
	(version 20260206)
	(generator "pcbnew")
	(generator_version "10.0")
	(general
		(thickness 1.6)
		(legacy_teardrops no)
	)
	(paper "A4")
	(title_block
		(title "03242023_DA0F0TMBIJ0_F0T_Motherboard_J_brd_V01_OCP.brd")
		(comment 1 "Grand Teton / footprints 1467-1469 of 6105")
	)
	(layers
		(0 "F.Cu" signal "TOP")
		(4 "In1.Cu" signal "GND")
		(6 "In2.Cu" signal "IN1")
		(8 "In3.Cu" signal "GND1")
		(10 "In4.Cu" signal "IN2")
		(12 "In5.Cu" signal "GND2")
		(14 "In6.Cu" signal "IN3")
		(16 "In7.Cu" signal "GND3")
		(18 "In8.Cu" signal "VCC")
		(20 "In9.Cu" signal "VCC1")
		(22 "In10.Cu" signal "GND4")
		(24 "In11.Cu" signal "IN4")
		(26 "In12.Cu" signal "GND5")
		(28 "In13.Cu" signal "IN5")
		(30 "In14.Cu" signal "GND6")
		(32 "In15.Cu" signal "IN6")
		(34 "In16.Cu" signal "GND7")
		(2 "B.Cu" signal "BOTTOM")
		(9 "F.Adhes" user "F.Adhesive")
		(11 "B.Adhes" user "B.Adhesive")
		(13 "F.Paste" user "Package Geometry/Pastemask Top")
		(15 "B.Paste" user "Package Geometry/Pastemask Bottom")
		(5 "F.SilkS" user "Ref Des/Silkscreen Top")
		(7 "B.SilkS" user "Ref Des/Silkscreen Bottom")
		(1 "F.Mask" user "Board Geometry/Soldermask Top")
		(3 "B.Mask" user "Board Geometry/Soldermask Bottom")
		(17 "Dwgs.User" user "User.Drawings")
		(19 "Cmts.User" user "User.Comments")
		(21 "Eco1.User" user "User.Eco1")
		(23 "Eco2.User" user "User.Eco2")
		(25 "Edge.Cuts" user "Board Geometry/Outline")
		(27 "Margin" user)
		(31 "F.CrtYd" user "Package Geometry/Place Bound Top")
		(29 "B.CrtYd" user "Package Geometry/Place Bound Bottom")
		(35 "F.Fab" user "Ref Des/Assembly Top")
		(33 "B.Fab" user "Ref Des/Assembly Bottom")
	)
	(footprint ""
		(layer "F.Cu")
		(at 366.48263 -258.726686 90)
		(property "Reference" "C976"
			(at 0 0 90)
			(layer "F.SilkS")
			(hide yes)
			(effects
				(font
					(size 1.27 1.27)
				)
			)
		)
		(property "Value" ""
			(at 0 0 90)
			(layer "F.Fab")
			(effects
				(font
					(size 1.27 1.27)
				)
			)
		)
		(duplicate_pad_numbers_are_jumpers no)
		(fp_line
			(start 0.7874 -0.4064)
			(end 0.7874 0.4064)
			(stroke
				(width 0.1524)
				(type default)
			)
			(layer "F.SilkS")
		)
		(fp_line
			(start -0.7874 -0.4064)
			(end 0.7874 -0.4064)
			(stroke
				(width 0.1524)
				(type default)
			)
			(layer "F.SilkS")
		)
		(fp_line
			(start 0.7874 0.4064)
			(end -0.7874 0.4064)
			(stroke
				(width 0.1524)
				(type default)
			)
			(layer "F.SilkS")
		)
		(fp_line
			(start -0.7874 0.4064)
			(end -0.7874 -0.4064)
			(stroke
				(width 0.1524)
				(type default)
			)
			(layer "F.SilkS")
		)
		(fp_line
			(start -0.12065 -0.305054)
			(end -0.12065 -0.2794)
			(stroke
				(width 0.1)
				(type default)
			)
			(layer "F.Fab")
		)
		(fp_line
			(start -0.67945 -0.305054)
			(end -0.12065 -0.305054)
			(stroke
				(width 0.1)
				(type default)
			)
			(layer "F.Fab")
		)
		(fp_line
			(start 0.67945 -0.3048)
			(end 0.67945 0.3048)
			(stroke
				(width 0.1)
				(type default)
			)
			(layer "F.Fab")
		)
		(fp_line
			(start 0.12065 -0.3048)
			(end 0.67945 -0.3048)
			(stroke
				(width 0.1)
				(type default)
			)
			(layer "F.Fab")
		)
		(fp_line
			(start 0.12065 -0.2794)
			(end 0.12065 -0.3048)
			(stroke
				(width 0.1)
				(type default)
			)
			(layer "F.Fab")
		)
		(fp_line
			(start -0.12065 -0.2794)
			(end 0.12065 -0.2794)
			(stroke
				(width 0.1)
				(type default)
			)
			(layer "F.Fab")
		)
		(fp_line
			(start 0.120396 0.2794)
			(end -0.12065 0.2794)
			(stroke
				(width 0.1)
				(type default)
			)
			(layer "F.Fab")
		)
		(fp_line
			(start -0.12065 0.2794)
			(end -0.12065 0.3048)
			(stroke
				(width 0.1)
				(type default)
			)
			(layer "F.Fab")
		)
		(fp_line
			(start 0.67945 0.3048)
			(end 0.120396 0.3048)
			(stroke
				(width 0.1)
				(type default)
			)
			(layer "F.Fab")
		)
		(fp_line
			(start 0.120396 0.3048)
			(end 0.120396 0.2794)
			(stroke
				(width 0.1)
				(type default)
			)
			(layer "F.Fab")
		)
		(fp_line
			(start -0.12065 0.3048)
			(end -0.67945 0.3048)
			(stroke
				(width 0.1)
				(type default)
			)
			(layer "F.Fab")
		)
		(fp_line
			(start -0.67945 0.3048)
			(end -0.67945 -0.305054)
			(stroke
				(width 0.1)
				(type default)
			)
			(layer "F.Fab")
		)
		(pad "1" smd circle
			(at -0.40005 0 90)
			(size 0 0)
			(layers "F.Cu" "F.Mask" "F.Paste")
			(net "PVCCIN_CPU0")
		)
		(pad "2" smd circle
			(at 0.40005 0 90)
			(size 0 0)
			(layers "F.Cu" "F.Mask" "F.Paste")
			(net "GND")
		)
	)
	(footprint ""
		(layer "F.Cu")
		(at 27.6352 -409.0416 -90)
		(property "Reference" "C1978"
			(at 0 0 270)
			(layer "F.SilkS")
			(hide yes)
			(effects
				(font
					(size 1.27 1.27)
				)
			)
		)
		(property "Value" ""
			(at 0 0 270)
			(layer "F.Fab")
			(effects
				(font
					(size 1.27 1.27)
				)
			)
		)
		(duplicate_pad_numbers_are_jumpers no)
		(fp_line
			(start -0.7874 0.4064)
			(end -0.7874 -0.4064)
			(stroke
				(width 0.1524)
				(type default)
			)
			(layer "F.SilkS")
		)
		(fp_line
			(start 0.7874 0.4064)
			(end -0.7874 0.4064)
			(stroke
				(width 0.1524)
				(type default)
			)
			(layer "F.SilkS")
		)
		(fp_line
			(start -0.7874 -0.4064)
			(end 0.7874 -0.4064)
			(stroke
				(width 0.1524)
				(type default)
			)
			(layer "F.SilkS")
		)
		(fp_line
			(start 0.7874 -0.4064)
			(end 0.7874 0.4064)
			(stroke
				(width 0.1524)
				(type default)
			)
			(layer "F.SilkS")
		)
		(fp_line
			(start -0.67945 0.3048)
			(end -0.67945 -0.305054)
			(stroke
				(width 0.1)
				(type default)
			)
			(layer "F.Fab")
		)
		(fp_line
			(start -0.12065 0.3048)
			(end -0.67945 0.3048)
			(stroke
				(width 0.1)
				(type default)
			)
			(layer "F.Fab")
		)
		(fp_line
			(start 0.120396 0.3048)
			(end 0.120396 0.2794)
			(stroke
				(width 0.1)
				(type default)
			)
			(layer "F.Fab")
		)
		(fp_line
			(start 0.67945 0.3048)
			(end 0.120396 0.3048)
			(stroke
				(width 0.1)
				(type default)
			)
			(layer "F.Fab")
		)
		(fp_line
			(start -0.12065 0.2794)
			(end -0.12065 0.3048)
			(stroke
				(width 0.1)
				(type default)
			)
			(layer "F.Fab")
		)
		(fp_line
			(start 0.120396 0.2794)
			(end -0.12065 0.2794)
			(stroke
				(width 0.1)
				(type default)
			)
			(layer "F.Fab")
		)
		(fp_line
			(start -0.12065 -0.2794)
			(end 0.12065 -0.2794)
			(stroke
				(width 0.1)
				(type default)
			)
			(layer "F.Fab")
		)
		(fp_line
			(start 0.12065 -0.2794)
			(end 0.12065 -0.3048)
			(stroke
				(width 0.1)
				(type default)
			)
			(layer "F.Fab")
		)
		(fp_line
			(start 0.12065 -0.3048)
			(end 0.67945 -0.3048)
			(stroke
				(width 0.1)
				(type default)
			)
			(layer "F.Fab")
		)
		(fp_line
			(start 0.67945 -0.3048)
			(end 0.67945 0.3048)
			(stroke
				(width 0.1)
				(type default)
			)
			(layer "F.Fab")
		)
		(fp_line
			(start -0.67945 -0.305054)
			(end -0.12065 -0.305054)
			(stroke
				(width 0.1)
				(type default)
			)
			(layer "F.Fab")
		)
		(fp_line
			(start -0.12065 -0.305054)
			(end -0.12065 -0.2794)
			(stroke
				(width 0.1)
				(type default)
			)
			(layer "F.Fab")
		)
		(pad "1" smd circle
			(at -0.40005 0 270)
			(size 0 0)
			(layers "F.Cu" "F.Mask" "F.Paste")
			(net "GPU_PRSNT_N_ISO")
		)
		(pad "2" smd circle
			(at 0.40005 0 270)
			(size 0 0)
			(layers "F.Cu" "F.Mask" "F.Paste")
			(net "GND")
		)
	)
	(footprint ""
		(layer "F.Cu")
		(at 443.7507 -51.059588 -90)
		(property "Reference" "C1333"
			(at 0 0 270)
			(layer "F.SilkS")
			(hide yes)
			(effects
				(font
					(size 1.27 1.27)
				)
			)
		)
		(property "Value" ""
			(at 0 0 270)
			(layer "F.Fab")
			(effects
				(font
					(size 1.27 1.27)
				)
			)
		)
		(duplicate_pad_numbers_are_jumpers no)
		(fp_line
			(start -1.524 0.762)
			(end -1.524 -0.762)
			(stroke
				(width 0.1524)
				(type default)
			)
			(layer "F.SilkS")
		)
		(fp_line
			(start 1.524 0.762)
			(end -1.524 0.762)
			(stroke
				(width 0.1524)
				(type default)
			)
			(layer "F.SilkS")
		)
		(fp_line
			(start -1.524 -0.762)
			(end 1.524 -0.762)
			(stroke
				(width 0.1524)
				(type default)
			)
			(layer "F.SilkS")
		)
		(fp_line
			(start 1.524 -0.762)
			(end 1.524 0.762)
			(stroke
				(width 0.1524)
				(type default)
			)
			(layer "F.SilkS")
		)
		(fp_line
			(start -1.1049 0.724916)
			(end 1.1049 0.724916)
			(stroke
				(width 0.1)
				(type default)
			)
			(layer "F.Fab")
		)
		(fp_line
			(start 1.1049 0.724916)
			(end 1.1049 -0.724916)
			(stroke
				(width 0.1)
				(type default)
			)
			(layer "F.Fab")
		)
		(fp_line
			(start -1.1049 -0.724916)
			(end -1.1049 0.724916)
			(stroke
				(width 0.1)
				(type default)
			)
			(layer "F.Fab")
		)
		(fp_line
			(start 1.1049 -0.724916)
			(end -1.1049 -0.724916)
			(stroke
				(width 0.1)
				(type default)
			)
			(layer "F.Fab")
		)
		(pad "1" smd rect
			(at -0.889 0 90)
			(size 1.016 1.27)
			(layers "F.Cu" "F.Mask" "F.Paste")
			(net "P3V3_AUX")
		)
		(pad "2" smd rect
			(at 0.889 0 90)
			(size 1.016 1.27)
			(layers "F.Cu" "F.Mask" "F.Paste")
			(net "GND")
		)
	)
)
